(kicad_pcb
	(version 20260206)
	(generator "pcbnew")
	(generator_version "10.0")
	(general
		(thickness 1.6)
		(legacy_teardrops no)
	)
	(paper "A4")
	(title_block
		(title "timecard-production-celestica-r4006 — R4006-B0001-02_R01.brd")
		(comment 1 "Time Appliance Project (Time Card) / footprints 665-670 of 1113")
	)
	(layers
		(0 "F.Cu" signal "TOP")
		(4 "In1.Cu" signal "L02_GND1")
		(6 "In2.Cu" signal "L03_SIG1")
		(8 "In3.Cu" signal "L04_GND2")
		(10 "In4.Cu" signal "L05_VCC1")
		(12 "In5.Cu" signal "L06_VCC2")
		(14 "In6.Cu" signal "L07_GND3")
		(16 "In7.Cu" signal "L08_SIG2")
		(18 "In8.Cu" signal "L09_GND4")
		(2 "B.Cu" signal "BOTTOM")
		(9 "F.Adhes" user "F.Adhesive")
		(11 "B.Adhes" user "B.Adhesive")
		(13 "F.Paste" user "Package Geometry/Pastemask Top")
		(15 "B.Paste" user "Package Geometry/Pastemask Bottom")
		(5 "F.SilkS" user "Ref Des/Silkscreen Top")
		(7 "B.SilkS" user "Ref Des/Silkscreen Bottom")
		(1 "F.Mask" user "Board Geometry/Soldermask Top")
		(3 "B.Mask" user "Board Geometry/Soldermask Bottom")
		(17 "Dwgs.User" user "User.Drawings")
		(19 "Cmts.User" user "User.Comments")
		(21 "Eco1.User" user "User.Eco1")
		(23 "Eco2.User" user "User.Eco2")
		(25 "Edge.Cuts" user "Board Geometry/Outline")
		(27 "Margin" user)
		(31 "F.CrtYd" user "Package Geometry/Place Bound Top")
		(29 "B.CrtYd" user "Package Geometry/Place Bound Bottom")
		(35 "F.Fab" user "Ref Des/Assembly Top")
		(33 "B.Fab" user "Ref Des/Assembly Bottom")
	)
	(footprint ""
		(layer "F.Cu")
		(at 140.1318 -21.9202)
		(property "Reference" "C239"
			(at -3.2258 -1.02743 0)
			(unlocked yes)
			(layer "F.SilkS")
			(effects
				(font
					(size 0.7874 0.5842)
					(thickness 0.1524)
				)
			)
		)
		(property "Value" "VAL*"
			(at 0.0762 3.134106 0)
			(unlocked yes)
			(layer "F.Fab")
			(hide yes)
			(effects
				(font
					(size 0.7874 0.5842)
					(thickness 0.1524)
				)
			)
		)
		(property "Tolerance" "TOL*"
			(at 0.0762 4.048506 0)
			(unlocked yes)
			(layer "Cmts.User")
			(hide yes)
			(effects
				(font
					(size 0.7874 0.5842)
					(thickness 0.1524)
				)
			)
		)
		(property "User Part Number" "PARTNUM*"
			(at 0.1016 5.013706 0)
			(unlocked yes)
			(layer "Cmts.User")
			(hide yes)
			(effects
				(font
					(size 0.7874 0.5842)
					(thickness 0.1524)
				)
			)
		)
		(property "Device Type" "CAPACITOR-G107-0F106-EM,10UF,2A"
			(at 0.0508 2.194306 0)
			(unlocked yes)
			(layer "F.Fab")
			(hide yes)
			(effects
				(font
					(size 0.7874 0.5842)
					(thickness 0.1524)
				)
			)
		)
		(duplicate_pad_numbers_are_jumpers no)
		(fp_line
			(start -1.5748 -0.9398)
			(end -1.5748 0.9398)
			(stroke
				(width 0.1)
				(type default)
			)
			(layer "F.SilkS")
		)
		(fp_line
			(start -1.5748 0.9398)
			(end 1.5748 0.9398)
			(stroke
				(width 0.1)
				(type default)
			)
			(layer "F.SilkS")
		)
		(fp_line
			(start 1.5748 -0.9398)
			(end -1.5748 -0.9398)
			(stroke
				(width 0.1)
				(type default)
			)
			(layer "F.SilkS")
		)
		(fp_line
			(start 1.5748 0.9398)
			(end 1.5748 -0.9398)
			(stroke
				(width 0.1)
				(type default)
			)
			(layer "F.SilkS")
		)
		(fp_rect
			(start 1.5748 -0.9398)
			(end -1.5748 0.9398)
			(stroke
				(width 0)
				(type default)
			)
			(fill no)
			(layer "F.CrtYd")
		)
		(fp_line
			(start -1.016 -0.635)
			(end -1.016 0.635)
			(stroke
				(width 0.1)
				(type default)
			)
			(layer "F.Fab")
		)
		(fp_line
			(start -1.016 0.635)
			(end 1.016 0.635)
			(stroke
				(width 0.1)
				(type default)
			)
			(layer "F.Fab")
		)
		(fp_line
			(start 1.016 -0.635)
			(end -1.016 -0.635)
			(stroke
				(width 0.1)
				(type default)
			)
			(layer "F.Fab")
		)
		(fp_line
			(start 1.016 0.635)
			(end 1.016 -0.635)
			(stroke
				(width 0.1)
				(type default)
			)
			(layer "F.Fab")
		)
		(pad "1" smd rect
			(at -0.8382 0)
			(size 0.9652 1.3716)
			(layers "F.Cu" "F.Mask" "F.Paste")
			(net "XP2R5V_FPGA")
		)
		(pad "2" smd rect
			(at 0.8382 0)
			(size 0.9652 1.3716)
			(layers "F.Cu" "F.Mask" "F.Paste")
			(net "SG")
		)
		(zone
			(layer "F.Cu")
			(hatch none 0.5)
			(connect_pads
				(clearance 0)
			)
			(min_thickness 0.25)
			(keepout
				(tracks allowed)
				(vias not_allowed)
				(pads allowed)
				(copperpour not_allowed)
				(footprints allowed)
			)
			(placement
				(enabled no)
				(sheetname "")
			)
			(fill
				(thermal_gap 0.5)
				(thermal_bridge_width 0.5)
				(island_removal_mode 0)
			)
			(polygon
				(pts
					(xy 140.3604 -22.5552) (xy 139.9032 -22.5552) (xy 139.9032 -21.2852) (xy 140.3604 -21.2852)
				)
			)
		)
	)
	(footprint ""
		(layer "F.Cu")
		(at 123.215908 -96.270064 90)
		(property "Reference" "P2"
			(at -0.932434 -4.089908 0)
			(unlocked yes)
			(layer "F.SilkS")
			(effects
				(font
					(size 0.7874 0.5842)
					(thickness 0.1524)
				)
			)
		)
		(property "Value" ""
			(at 0 0 90)
			(layer "F.Fab")
			(effects
				(font
					(size 1.27 1.27)
				)
			)
		)
		(property "User Part Number" "PARTNUM*"
			(at 0 5.311902 90)
			(unlocked yes)
			(layer "Cmts.User")
			(hide yes)
			(effects
				(font
					(size 0.7874 0.5842)
					(thickness 0.1524)
				)
			)
		)
		(property "Device Type" "CONN_HDR_2X4_F_S_SMT-G200-1307A"
			(at 0 4.118102 90)
			(unlocked yes)
			(layer "F.Fab")
			(hide yes)
			(effects
				(font
					(size 0.7874 0.5842)
					(thickness 0.1524)
				)
			)
		)
		(duplicate_pad_numbers_are_jumpers no)
		(fp_line
			(start 4.52755 -3.008884)
			(end 4.52755 3.009138)
			(stroke
				(width 0.1)
				(type default)
			)
			(layer "F.SilkS")
		)
		(fp_line
			(start -4.52755 -3.008884)
			(end 4.52755 -3.008884)
			(stroke
				(width 0.1)
				(type default)
			)
			(layer "F.SilkS")
		)
		(fp_line
			(start 4.52755 3.009138)
			(end -4.52755 3.009138)
			(stroke
				(width 0.1)
				(type default)
			)
			(layer "F.SilkS")
		)
		(fp_line
			(start -4.52755 3.009138)
			(end -4.52755 -3.008884)
			(stroke
				(width 0.1)
				(type default)
			)
			(layer "F.SilkS")
		)
		(fp_rect
			(start -4.78155 -3.262884)
			(end 4.78155 3.263138)
			(stroke
				(width 0)
				(type default)
			)
			(fill no)
			(layer "F.CrtYd")
		)
		(fp_line
			(start 4.27355 -2.06502)
			(end 4.27355 2.06502)
			(stroke
				(width 0.1)
				(type default)
			)
			(layer "F.Fab")
		)
		(fp_line
			(start -4.27355 -2.06502)
			(end 4.27355 -2.06502)
			(stroke
				(width 0.1)
				(type default)
			)
			(layer "F.Fab")
		)
		(fp_line
			(start 4.27355 2.06502)
			(end -4.27355 2.06502)
			(stroke
				(width 0.1)
				(type default)
			)
			(layer "F.Fab")
		)
		(fp_line
			(start -4.27355 2.06502)
			(end -4.27355 -2.06502)
			(stroke
				(width 0.1)
				(type default)
			)
			(layer "F.Fab")
		)
		(fp_text user "8"
			(at -3.218434 -3.962908 0)
			(unlocked yes)
			(layer "F.SilkS")
			(effects
				(font
					(size 0.7874 0.5842)
					(thickness 0.1524)
				)
			)
		)
		(fp_text user "2"
			(at 2.115566 -3.581908 0)
			(unlocked yes)
			(layer "F.SilkS")
			(effects
				(font
					(size 0.7874 0.5842)
					(thickness 0.1524)
				)
			)
		)
		(fp_text user "1"
			(at 3.004566 3.657092 0)
			(unlocked yes)
			(layer "F.SilkS")
			(effects
				(font
					(size 0.7874 0.5842)
					(thickness 0.1524)
				)
			)
		)
		(fp_text user "7"
			(at -2.329434 4.038092 0)
			(unlocked yes)
			(layer "F.SilkS")
			(effects
				(font
					(size 0.7874 0.5842)
					(thickness 0.1524)
				)
			)
		)
		(fp_text user "8"
			(at -3.205734 -2.946908 0)
			(unlocked yes)
			(layer "F.Fab")
			(effects
				(font
					(size 0.7874 0.5842)
					(thickness 0.1524)
				)
			)
		)
		(fp_text user "2"
			(at 3.525266 -2.819908 0)
			(unlocked yes)
			(layer "F.Fab")
			(effects
				(font
					(size 0.7874 0.5842)
					(thickness 0.1524)
				)
			)
		)
		(fp_text user "1"
			(at 3.398266 2.641092 0)
			(unlocked yes)
			(layer "F.Fab")
			(effects
				(font
					(size 0.7874 0.5842)
					(thickness 0.1524)
				)
			)
		)
		(fp_text user "7"
			(at -3.280664 2.932938 0)
			(unlocked yes)
			(layer "F.Fab")
			(effects
				(font
					(size 0.7874 0.5842)
					(thickness 0.1524)
				)
			)
		)
		(pad "1" smd rect
			(at 2.999994 1.637538 90)
			(size 1.016 2.2352)
			(layers "F.Cu" "F.Mask" "F.Paste")
			(net "XP5R0V_VCC_ANT")
		)
		(pad "2" smd rect
			(at 2.999994 -1.637284 90)
			(size 1.016 2.2352)
			(layers "F.Cu" "F.Mask" "F.Paste")
			(net "XP3R3V_GPS")
		)
		(pad "3" smd rect
			(at 0.999998 1.637538 90)
			(size 1.016 2.2352)
			(layers "F.Cu" "F.Mask" "F.Paste")
			(net "GPS_UART_TXD")
		)
		(pad "4" smd rect
			(at 0.999998 -1.637284 90)
			(size 1.016 2.2352)
			(layers "F.Cu" "F.Mask" "F.Paste")
			(net "GPS_RST_N")
		)
		(pad "5" smd rect
			(at -0.999998 1.637538 90)
			(size 1.016 2.2352)
			(layers "F.Cu" "F.Mask" "F.Paste")
			(net "GPS_UART_RXD")
		)
		(pad "6" smd rect
			(at -0.999998 -1.637284 90)
			(size 1.016 2.2352)
			(layers "F.Cu" "F.Mask" "F.Paste")
			(net "GPSTP1_OUT")
		)
		(pad "7" smd rect
			(at -2.999994 1.637538 90)
			(size 1.016 2.2352)
			(layers "F.Cu" "F.Mask" "F.Paste")
			(net "GPSTP2_OUT")
		)
		(pad "8" smd rect
			(at -2.999994 -1.637284 90)
			(size 1.016 2.2352)
			(layers "F.Cu" "F.Mask" "F.Paste")
			(net "SG")
		)
	)
	(footprint ""
		(layer "F.Cu")
		(at 109.22 -98.171)
		(property "Reference" "TP25"
			(at -0.9144 1.04775 0)
			(unlocked yes)
			(layer "F.SilkS")
			(effects
				(font
					(size 0.635 0.4064)
					(thickness 0.1524)
				)
				(justify left)
			)
		)
		(property "Value" ""
			(at 0 0 0)
			(layer "F.Fab")
			(effects
				(font
					(size 1.27 1.27)
				)
			)
		)
		(property "Device Type" "TP_PIONT-TP010CT020B030_PTH-TPA"
			(at -1.341882 0.996696 0)
			(unlocked yes)
			(layer "F.Fab")
			(hide yes)
			(effects
				(font
					(size 0.7874 0.5842)
					(thickness 0.000001)
				)
				(justify left)
			)
		)
		(duplicate_pad_numbers_are_jumpers no)
		(fp_poly
			(pts
				(arc
					(start 0.889 0)
					(mid -0.889 0)
					(end 0.889 0)
				)
			)
			(stroke
				(width 0)
				(type default)
			)
			(fill no)
			(layer "B.CrtYd")
		)
		(fp_poly
			(pts
				(arc
					(start 0.889 0)
					(mid -0.889 0)
					(end 0.889 0)
				)
			)
			(stroke
				(width 0)
				(type default)
			)
			(fill no)
			(layer "F.CrtYd")
		)
		(pad "1" thru_hole circle
			(at 0 0)
			(size 0.508 0.508)
			(drill 0.254)
			(layers "*.Cu" "*.Mask")
			(remove_unused_layers no)
			(net "RGB_LED_SHUTDOWN_N")
			(clearance 0.1016)
			(padstack
				(mode front_inner_back)
				(layer "Inner"
					(shape circle)
					(size 0.508 0.508)
					(clearance 0.1016)
				)
				(layer "B.Cu"
					(shape circle)
					(size 0.762 0.762)
					(clearance -0.0254)
				)
			)
		)
	)
	(footprint ""
		(layer "F.Cu")
		(at 89.281 -96.012 180)
		(property "Reference" "R38"
			(at -1.651 -2.32537 0)
			(unlocked yes)
			(layer "F.SilkS")
			(effects
				(font
					(size 0.7874 0.5842)
					(thickness 0.1524)
				)
			)
		)
		(property "Value" "VAL*"
			(at 0.02032 2.13233 180)
			(unlocked yes)
			(layer "F.Fab")
			(hide yes)
			(effects
				(font
					(size 0.7874 0.5842)
					(thickness 0.1524)
				)
			)
		)
		(property "Tolerance" "TOL*"
			(at 0.044704 3.05435 180)
			(unlocked yes)
			(layer "Cmts.User")
			(hide yes)
			(effects
				(font
					(size 0.7874 0.5842)
					(thickness 0.1524)
				)
			)
		)
		(property "User Part Number" "PARTNUM*"
			(at 0.02032 4.024884 180)
			(unlocked yes)
			(layer "Cmts.User")
			(hide yes)
			(effects
				(font
					(size 0.7874 0.5842)
					(thickness 0.1524)
				)
			)
		)
		(property "Device Type" "RESISTOR-G155-04421-01,4.42KOHA"
			(at 0.008382 1.210564 180)
			(unlocked yes)
			(layer "F.Fab")
			(hide yes)
			(effects
				(font
					(size 0.7874 0.5842)
					(thickness 0.1524)
				)
			)
		)
		(duplicate_pad_numbers_are_jumpers no)
		(fp_line
			(start 1.143 0.5588)
			(end 1.143 -0.5588)
			(stroke
				(width 0.1)
				(type default)
			)
			(layer "F.SilkS")
		)
		(fp_line
			(start 1.143 -0.5588)
			(end -1.143 -0.5588)
			(stroke
				(width 0.1)
				(type default)
			)
			(layer "F.SilkS")
		)
		(fp_line
			(start -1.143 0.5588)
			(end 1.143 0.5588)
			(stroke
				(width 0.1)
				(type default)
			)
			(layer "F.SilkS")
		)
		(fp_line
			(start -1.143 -0.5588)
			(end -1.143 0.5588)
			(stroke
				(width 0.1)
				(type default)
			)
			(layer "F.SilkS")
		)
		(fp_rect
			(start -1.143 -0.5588)
			(end 1.143 0.5588)
			(stroke
				(width 0)
				(type default)
			)
			(fill no)
			(layer "F.CrtYd")
		)
		(fp_line
			(start 0.508 0.3048)
			(end 0.508 -0.3048)
			(stroke
				(width 0.1)
				(type default)
			)
			(layer "F.Fab")
		)
		(fp_line
			(start 0.508 -0.3048)
			(end -0.508 -0.3048)
			(stroke
				(width 0.1)
				(type default)
			)
			(layer "F.Fab")
		)
		(fp_line
			(start -0.508 0.3048)
			(end 0.508 0.3048)
			(stroke
				(width 0.1)
				(type default)
			)
			(layer "F.Fab")
		)
		(fp_line
			(start -0.508 -0.3048)
			(end -0.508 0.3048)
			(stroke
				(width 0.1)
				(type default)
			)
			(layer "F.Fab")
		)
		(pad "1" smd rect
			(at -0.5334 0 180)
			(size 0.7112 0.6096)
			(layers "F.Cu" "F.Mask" "F.Paste")
			(net "XP3R3V_FB_R_TO_AGND")
		)
		(pad "2" smd rect
			(at 0.5334 0 180)
			(size 0.7112 0.6096)
			(layers "F.Cu" "F.Mask" "F.Paste")
			(net "XP3R3V_AGND")
		)
		(zone
			(layer "F.Cu")
			(hatch none 0.5)
			(connect_pads
				(clearance 0)
			)
			(min_thickness 0.25)
			(keepout
				(tracks allowed)
				(vias not_allowed)
				(pads allowed)
				(copperpour not_allowed)
				(footprints allowed)
			)
			(placement
				(enabled no)
				(sheetname "")
			)
			(fill
				(thermal_gap 0.5)
				(thermal_bridge_width 0.5)
				(island_removal_mode 0)
			)
			(polygon
				(pts
					(xy 89.3572 -95.7072) (xy 89.3572 -96.3168) (xy 89.2048 -96.3168) (xy 89.2048 -95.7072)
				)
			)
		)
	)
	(footprint ""
		(layer "F.Cu")
		(at 159.7406 -50.590196 -90)
		(property "Reference" "C63"
			(at -1.098804 3.11023 90)
			(unlocked yes)
			(layer "F.SilkS")
			(effects
				(font
					(size 0.7874 0.5842)
					(thickness 0.1524)
				)
			)
		)
		(property "Value" "VAL*"
			(at 0.0762 2.067306 270)
			(unlocked yes)
			(layer "F.Fab")
			(hide yes)
			(effects
				(font
					(size 0.7874 0.5842)
					(thickness 0.1524)
				)
			)
		)
		(property "Tolerance" "TOL*"
			(at 0.0762 3.032506 270)
			(unlocked yes)
			(layer "Cmts.User")
			(hide yes)
			(effects
				(font
					(size 0.7874 0.5842)
					(thickness 0.1524)
				)
			)
		)
		(property "User Part Number" "PARTNUM*"
			(at 0.1016 4.023106 270)
			(unlocked yes)
			(layer "Cmts.User")
			(hide yes)
			(effects
				(font
					(size 0.7874 0.5842)
					(thickness 0.1524)
				)
			)
		)
		(property "Device Type" "CAPACITOR-G105-0B104-EK,0.1UF,A"
			(at 0.0508 1.127506 270)
			(unlocked yes)
			(layer "F.Fab")
			(hide yes)
			(effects
				(font
					(size 0.7874 0.5842)
					(thickness 0.1524)
				)
			)
		)
		(duplicate_pad_numbers_are_jumpers no)
		(fp_line
			(start -1.143 0.5588)
			(end 1.143 0.5588)
			(stroke
				(width 0.1)
				(type default)
			)
			(layer "F.SilkS")
		)
		(fp_line
			(start 1.143 0.5588)
			(end 1.143 -0.5588)
			(stroke
				(width 0.1)
				(type default)
			)
			(layer "F.SilkS")
		)
		(fp_line
			(start -1.143 -0.5588)
			(end -1.143 0.5588)
			(stroke
				(width 0.1)
				(type default)
			)
			(layer "F.SilkS")
		)
		(fp_line
			(start 1.143 -0.5588)
			(end -1.143 -0.5588)
			(stroke
				(width 0.1)
				(type default)
			)
			(layer "F.SilkS")
		)
		(fp_rect
			(start 1.143 -0.5588)
			(end -1.143 0.5588)
			(stroke
				(width 0)
				(type default)
			)
			(fill no)
			(layer "F.CrtYd")
		)
		(fp_line
			(start -0.508 0.3048)
			(end 0.508 0.3048)
			(stroke
				(width 0.1)
				(type default)
			)
			(layer "F.Fab")
		)
		(fp_line
			(start 0.508 0.3048)
			(end 0.508 -0.3048)
			(stroke
				(width 0.1)
				(type default)
			)
			(layer "F.Fab")
		)
		(fp_line
			(start -0.508 -0.3048)
			(end -0.508 0.3048)
			(stroke
				(width 0.1)
				(type default)
			)
			(layer "F.Fab")
		)
		(fp_line
			(start 0.508 -0.3048)
			(end -0.508 -0.3048)
			(stroke
				(width 0.1)
				(type default)
			)
			(layer "F.Fab")
		)
		(pad "1" smd rect
			(at -0.5334 0 270)
			(size 0.7112 0.6096)
			(layers "F.Cu" "F.Mask" "F.Paste")
			(net "XP5R0V_USB_CONN")
		)
		(pad "2" smd rect
			(at 0.5334 0 270)
			(size 0.7112 0.6096)
			(layers "F.Cu" "F.Mask" "F.Paste")
			(net "SG")
		)
		(zone
			(layer "F.Cu")
			(hatch none 0.5)
			(connect_pads
				(clearance 0)
			)
			(min_thickness 0.25)
			(keepout
				(tracks allowed)
				(vias not_allowed)
				(pads allowed)
				(copperpour not_allowed)
				(footprints allowed)
			)
			(placement
				(enabled no)
				(sheetname "")
			)
			(fill
				(thermal_gap 0.5)
				(thermal_bridge_width 0.5)
				(island_removal_mode 0)
			)
			(polygon
				(pts
					(xy 160.0454 -50.513996) (xy 160.0454 -50.666396) (xy 159.4358 -50.666396) (xy 159.4358 -50.513996)
				)
			)
		)
	)
	(footprint ""
		(layer "F.Cu")
		(at 93.0148 -76.1238 -90)
		(property "Reference" "C182"
			(at -18.9992 27.06243 90)
			(unlocked yes)
			(layer "F.SilkS")
			(effects
				(font
					(size 0.7874 0.5842)
					(thickness 0.1524)
				)
			)
		)
		(property "Value" "VAL*"
			(at 0.0762 2.067306 270)
			(unlocked yes)
			(layer "F.Fab")
			(hide yes)
			(effects
				(font
					(size 0.7874 0.5842)
					(thickness 0.1524)
				)
			)
		)
		(property "Tolerance" "TOL*"
			(at 0.0762 3.032506 270)
			(unlocked yes)
			(layer "Cmts.User")
			(hide yes)
			(effects
				(font
					(size 0.7874 0.5842)
					(thickness 0.1524)
				)
			)
		)
		(property "User Part Number" "PARTNUM*"
			(at 0.1016 4.023106 270)
			(unlocked yes)
			(layer "Cmts.User")
			(hide yes)
			(effects
				(font
					(size 0.7874 0.5842)
					(thickness 0.1524)
				)
			)
		)
		(property "Device Type" "CAPACITOR-G105-0B104-EK,0.1UF,A"
			(at 0.0508 1.127506 270)
			(unlocked yes)
			(layer "F.Fab")
			(hide yes)
			(effects
				(font
					(size 0.7874 0.5842)
					(thickness 0.1524)
				)
			)
		)
		(duplicate_pad_numbers_are_jumpers no)
		(fp_line
			(start -1.143 0.5588)
			(end 1.143 0.5588)
			(stroke
				(width 0.1)
				(type default)
			)
			(layer "F.SilkS")
		)
		(fp_line
			(start 1.143 0.5588)
			(end 1.143 -0.5588)
			(stroke
				(width 0.1)
				(type default)
			)
			(layer "F.SilkS")
		)
		(fp_line
			(start -1.143 -0.5588)
			(end -1.143 0.5588)
			(stroke
				(width 0.1)
				(type default)
			)
			(layer "F.SilkS")
		)
		(fp_line
			(start 1.143 -0.5588)
			(end -1.143 -0.5588)
			(stroke
				(width 0.1)
				(type default)
			)
			(layer "F.SilkS")
		)
		(fp_rect
			(start -1.143 0.5588)
			(end 1.143 -0.5588)
			(stroke
				(width 0)
				(type default)
			)
			(fill no)
			(layer "F.CrtYd")
		)
		(fp_line
			(start -0.508 0.3048)
			(end 0.508 0.3048)
			(stroke
				(width 0.1)
				(type default)
			)
			(layer "F.Fab")
		)
		(fp_line
			(start 0.508 0.3048)
			(end 0.508 -0.3048)
			(stroke
				(width 0.1)
				(type default)
			)
			(layer "F.Fab")
		)
		(fp_line
			(start -0.508 -0.3048)
			(end -0.508 0.3048)
			(stroke
				(width 0.1)
				(type default)
			)
			(layer "F.Fab")
		)
		(fp_line
			(start 0.508 -0.3048)
			(end -0.508 -0.3048)
			(stroke
				(width 0.1)
				(type default)
			)
			(layer "F.Fab")
		)
		(pad "1" smd rect
			(at -0.5334 0 270)
			(size 0.7112 0.6096)
			(layers "F.Cu" "F.Mask" "F.Paste")
			(net "XP3R3V")
		)
		(pad "2" smd rect
			(at 0.5334 0 270)
			(size 0.7112 0.6096)
			(layers "F.Cu" "F.Mask" "F.Paste")
			(net "SG")
		)
		(zone
			(layer "F.Cu")
			(hatch none 0.5)
			(connect_pads
				(clearance 0)
			)
			(min_thickness 0.25)
			(keepout
				(tracks allowed)
				(vias not_allowed)
				(pads allowed)
				(copperpour not_allowed)
				(footprints allowed)
			)
			(placement
				(enabled no)
				(sheetname "")
			)
			(fill
				(thermal_gap 0.5)
				(thermal_bridge_width 0.5)
				(island_removal_mode 0)
			)
			(polygon
				(pts
					(xy 92.71 -76.2) (xy 92.71 -76.0476) (xy 93.3196 -76.0476) (xy 93.3196 -76.2)
				)
			)
		)
	)
)
